 
 
Open CloudServer  
OCS Solid State Drive 
Version 2.0 
 
 
 
 
 
Author: 
Laura Caulfield, Software Engineer II, Microsoft 
 



Open Compute Project  Open CloudServer OCS Solid State Drive 
http://opencompute.org ii 
Revision History 
Date Description 
2/25/2015 Version 2.0 
 
  



Open Compute Project  Open CloudServer Solid State Drive 
http://opencompute.org iii 
 
© 2015 Microsoft Corporation. 
As of October 30, 2014, the following persons or entities have made this Specification available under the Open Web 
Foundation Final Specification Agreement (OWFa 1.0), which is available at http://www.openwebfoundation.org/legal/the-owf-
1-0-agreements/owfa-1-0 
 Microsoft Corporation.  
You can review the signed copies of the Open Web Foundation Agreement Version 1.0 for this Specification at 
http://opencompute.org/licensing/, which may also include additional parties to those listed above. 
Your use of this Specification may be subject to other third party rights. THIS SPECIFICATION IS PROVIDED "AS IS." The 
contributors expressly disclaim any warranties (express, implied, or otherwise), including implied warranties of merchantability, 
noninfringement, fitness for a particular purpose, or title, related to the Specification. The entire risk as to implementing or 
otherwise using the Specification is assumed by the Specification implementer and user. IN NO EVENT WILL ANY PARTY BE 
LIABLE TO ANY OTHER PARTY FOR LOST PROFITS OR ANY FORM OF INDIRECT, SPECIAL, INCIDENTAL, OR CONSEQUENTIAL 
DAMAGES OF ANY CHARACTER FROM ANY CAUSES OF ACTION OF ANY KIND WITH RESPECT TO THIS SPECIFICATION OR ITS 
GOVERNING AGREEMENT, WHETHER BASED ON BREACH OF CONTRACT, TORT (INCLUDING NEGLIGENCE), OR OTHERWISE, AND 
WHETHER OR NOT THE OTHER PARTY HAS BEEN ADVISED OF THE POSSIBILITY OF SUCH DAMAGE. 
CONTRIBUTORS AND LICENSORS OF THIS SPECIFICATION MAY HAVE MENTIONED CERTAIN TECHNOLOGIES THAT ARE MERELY 
REFERENCED WITHIN THIS SPECIFICATION AND NOT LICENSED UNDER THE OWF CLA OR OWFa. THE FOLLOWING IS A LIST OF 
MERELY REFERENCED TECHNOLOGY: INTELLIGENT PLATFORM MANAGEMENT INTERFACE (IPMI), I2C TRADEMARK OF PHILLIPS 
SEMICONDUCTOR. IMPLEMENTATION OF THESE TECHNOLOGIES MAY BE SUBJECT TO THEIR OWN LEGAL TERMS. 
  



 
iv February 25, 2015 
 
 
Contents 
1 Summary ....................................................................................................................................................... 1 
2 Reference Documents ................................................................................................................................... 1 
2.1 Applicable Documents .................................................................................................................................. 1 
2.2 Order of Preference ...................................................................................................................................... 2 
3 Operating System and Boot Requirements .................................................................................................... 2 
4 Performance .................................................................................................................................................. 2 
4.1 Bandwidth & Throughput ............................................................................................................................. 3 
4.2 Latency ......................................................................................................................................................... 3 
4.3 No I/O Throttling to Reduce Wear ............................................................................................................... 4 
5 Power ............................................................................................................................................................ 4 
5.1 NVMe Drives ................................................................................................................................................. 4 
5.2 AHCI Drives ................................................................................................................................................... 4 
6 Thermal & Mechanical .................................................................................................................................. 5 
6.1 Thermal ........................................................................................................................................................ 5 
6.2 Mechanical ................................................................................................................................................... 6 
7 Endurance ..................................................................................................................................................... 7 
8 S.M.A.R.T. Attributes ..................................................................................................................................... 7 
8.1 NVMe ......................................................................................................................................................... 10 
8.2 AHCI ............................................................................................................................................................ 10 
9 Commands .................................................................................................................................................. 10 
9.1 Firmware Update ....................................................................................................................................... 10 
9.2 Disk Reconditioning Tool & Crypto-Erase ................................................................................................... 10 
9.3 Debugging Logs .......................................................................................................................................... 11 
10 Unplanned Power Loss ................................................................................................................................ 11 
10.1 Drives with Volatile Write Cache ................................................................................................................ 11 
10.2 Drives with Non-Volatile Write Cache ........................................................................................................ 11 
10.2.1 System-Assisted NV Write Cache ...................................................................................................... 12 
10.2.2 Fast Flushing ...................................................................................................................................... 12 
11 Data Security ............................................................................................................................................... 12 
 
  



Open Compute Project  Open CloudServer Solid State Drive 
http://opencompute.org v 
 
Table of Figures 
Figure 1: Air Property Pictorial ...................................................................................................................... 5 
Figure 2: Memory Card Environmental Requirement .................................................................................. 6 
 
  



 
vi February 25, 2015 
 
Table of Tables 
Table 1: Device Summary .............................................................................................................................. 1 
Table 2: Reference Documents ..................................................................................................................... 2 
Table 3: Throughput Targets ......................................................................................................................... 3 
Table 4: Latency Targets ............................................................................................................................... 3 
Table 5: Additional SMART Attributes .......................................................................................................... 9 



 
http://opencompute.org 1 
 
1 Summary 
This specification, Open CloudServer Solid State Drive, OCS SSD, describes the low-cost, high-
performance flash-based storage devices deployed first in the Open CloudServer OCS Blade V2 
specification.  The OCS Blade V2 supports four PCI-Express riser cards and eight Open CloudServer Solid 
State Drive M.2 modules.  The Table 1 briefly describes the required features. 
Table 1: Device Summary 
Parameter Value 
Form Factor M.2 
Dimensions 22mm x 110mm (preferred) 
Hardware Protocol PCIe Generation 3, x4 (preferred) 
Software Protocol NVMe 1.1a (preferred), or AHCI over PCIe 
Capacity 480GB 
Endurance 3 DWPD over 3 years, or 
0.5 DWPD over 3 years 
Default Maximum Power 6W RMS over 100µs 
Unpowered Retention 1 week – 1 month 
Life (MTTF/AFR) 1.5M hrs. / 0.5% (JEDEC Specification) 
Ambient Operating Temperature 0˚C – 70 ˚C 
Duty Cycle 100% 
Sector Size 512 Bytes 
*1 GB = 1,000,000,000 Bytes 
2 Reference Documents 
This section lists the applicable reference documents and defines the order of preference. 
2.1 Applicable Documents 
Table 2 lists additional specifications to which the OCS SSD adheres.  



 
2 February 25, 2015 
 
Table 2: Reference Documents 
Reference Description 
M.2 “PCI Express M.2 Specification” Revision 0.7a, version 1.0.  PCI Express, 2013. 
NVM Express “NVM Express” Revision 1.1a. Intel, 2013. 
PCI Express “PCI Express Base Specification.”  Revision 3.1. PCI Express, 2014. 
SNIA “Solid State Storage (SSS) Performance Test Specification (PTS) Enterprise” Version 
1.0.  Advanced Storage and Information Technology (SNIA), 2011. 
JEDEC 218 “Solid-State Drive (SSD) Requirements and Endurance Test Method” JEDEC Solid 
State Technology Association (JEDEC), 2011. 
ACS3 “Information Technology – ATA/ATAPI Command Set – 3 (ACS3)” Revision 5, 
American National Standard, 2013. 
2.2 Order of Preference 
In the event of a conflict between this specification and references cited herein, this specification shall 
take precedence. 
3 Operating System and Boot Requirements 
The OCS SSD must support the following requirements. 
 As a boot drive, the drive must be support 64-bit Windows: WinPE and Windows Server 2012 
R2. 
 As a non-boot drive, the drive must be present in UEFI/BIOS. 
 Trimmed addresses must provide the performance and reliability benefits of additional OP. 
4 Performance 
The drive must meet the performance targets with these assumptions:  
 Entropy of all workloads is 100% (uncompressible) 
 Active range is 100% 
 Maximum power draw as specified  



Open Compute Project  Open CloudServer Solid State Drive 
http://opencompute.org 3 
 
 Operations are aligned to 4kB address boundaries 
 Performance targets include overheads from NTFS 
The vendor must provide a performance test report as defined by the SNIA Solid State Storage 
Performance Test Specification (PTSE). 
4.1 Bandwidth & Throughput 
The drive must meet or exceed the 6W performance targets list below.   
Table 3: Throughput Targets 
Metric 6W Target 
Sequential Read (MB/s)* 1600 
Sequential Write (MB/s)* 750 
Random Read (4kB IOPS) 70k 
Random Write (4kB IOPS) 20k 
Random Read/Write Mix 
(70/30 4kB IOPS) 
40k 
*MB = 106 Bytes 
4.2 Latency 
Random read latency must match or beat the distribution listed below under the following test 
conditions. 
 Queue Depth = 1 
 Drive is trimmed then written sequentially with 2MB accesses 
 Drive is near End-of-Life 
Table 4: Latency Targets 
 
 4kB ( µs ) 8kB ( µs ) 64kB ( µs ) Operations  
Needed 
in Test* 
Average  240  250 450 -- 
99 % (2 nines) 300  360 770 >100 
99.9 % (3 nines) 400  380 1,000 >1,000 
99.99 % (4 nines) 500  550 3,000 >10,000 
99.999 % (5 nines) 1,000 2,000 3,500 >1e5 
99.9999 % (6 nines) 3,000 4,000 5,000 >1e6  
99.99999 % (7 nines) 5,000 6,000 8,000 >1e7 
99.999999 % (8 nines) 7,000 8,000 10,000 >1e8 
99.9999999 % (9 nines) 9,000 10,000 15,000 >1e9 
Maximum Timeout  11,000 12,000 20,000 -- 
*The test must apply the minimum number of operations listed in the right-most column. 



 
4 February 25, 2015 
 
4.3 No I/O Throttling to Reduce Wear 
All SSD solutions are to provide performance consistent with the capabilities of the flash and controller.  
The drive: 
 Must not throttle the performance for the purpose of distributing wear on the flash over time 
 Must continue to allow writes as long as possible after the media wear indicator reaches 100% 
5 Power 
The drive must support dynamic switching between power states in which the host can perform I/O.   
The drive must report at least one power state for each level: 
 Required: Maximum of 6W,  
 Optional: Maximum of 8W and 10W 
Some blade configurations may leverage the optional power states for higher performance, but there is 
no guarantee.   
5.1 NVMe Drives 
NVMe drives must allow switching between Operational Power States through the Get Features and Set 
Features command with the Power Management feature identifier (see Figure 92 in Section 5.12.1.2 in 
the NVMe 1.1a specification).   
The supported operational power states shall be returned from the Get Features command with the 
Power Management feature identifier.  The Set Features command with Power Management feature 
identifier shall switch between the different supported operational power states.   
If the drive supports the Autonomous Power State Transition feature, it shall disable Autonomous Power 
State Transition if the host sets Autonomous Power State Transition Enable (APSTE) to 0 in the 
Autonomous Power State Transition Set Feature command.   
NVMe drives must support Get and Set Features command with Power Management feature identifier, 
and the Autonomous Power State Transition feature as described above. 
5.2 AHCI Drives 
The maximum power of AHCI drives will be set at server configuration time through Advanced Power 
Management.  The vendor must report which APM levels the drive has mapped to the power states 
defined above.  



Open Compute Project  Open CloudServer Solid State Drive 
http://opencompute.org 5 
 
AHCI drives must report which APM levels map to which power levels. 
6 Thermal & Mechanical 
6.1 Thermal 
The SSD must thermally protect itself from overheating.   
The drive must signal the host when its temperature is too high through a Temperature Async Event 
Notification (for NVMe) or Device Statistics Notification (DSN) (for AHCI). 
The environment in which the memory cards are expected to operate may vary from position to position 
within the server.  To best represent this environment, the air temperature and speed properties are 
defined as measured in Figure 1. 
 
Figure 1: Air Property Pictorial 


 
6 February 25, 2015 
 
The guidelines for the expected environment are shown in Figure 2.  The theoretical full performance 
line represents the worst case conditions in which the memory card is expected to operate at full 
performance.  The memory cards are expected to operate, but allowed to do so at a reduced 
performance in the conditions between the full performance line and the throttled performance line. 
The drive must operate in the thermal environment as shown in Figure 2. 
 
Figure 2: Memory Card Environmental Requirement 
 
6.2 Mechanical 
This section outlines the mechanical requirements. 
 The connector on the M.2 card must use 30 micro-inches of gold plating.                                      


Open Compute Project  Open CloudServer Solid State Drive 
http://opencompute.org 7 
 
 The server can mechanically support module lengths of 60mm, 80mm or 110mm and uses a 
Socket 3 connector.   
 The card shall conform to the geometry provided by the PCI Express M.2 Specification, section 
2.3.4.4, card type 22110. 
Note: Including capacitors for the power safe feature has proven difficult with the current height 
specification.  The OCS V2 blade can accommodate a top-side component height of 3.0 mm, as shown 
in Figure 3.  Vendors are granted an exception for this specification if 3.0 mm height is met.  Vendors 
are encouraged to meet the M.2 specification to ensure compatibility with future OCS systems and 
non-OCS systems. 
 
Figure 3: Top-Side Mechanical Exception 
7 Endurance 
Endurance is measured against the following reasonable worst-case workload: 
 4kB accesses aligned to 4kB boundaries 
 Random pattern of addresses 
 100% active range 
 100% full drive 
 0% compressible data 
Drives must meet the following endurance requirements 
 High endurance drives must be able to sustain 3 drive writes per day (DWPD) over 3 years 
 Low endurance drives must be able to sustain 0.5 drive writes per day (DWPD) over 3 years 
8 S.M.A.R.T. Attributes 
Consistent access to SMART attributes across all drives is required.  The NVMe specification provides 
this (for NVMe drives) through log pages.  AHCI drives leverage the ACS3 log pages.   



 
8 February 25, 2015 
 
 SMART commands may not block IO for more than 30ms. 
 SMART values will be updated before each read so that the value reported is the most current.  
 The vendor-specific log page should be 512 bytes and define the following attributes: 
  



Open Compute Project  Open CloudServer Solid State Drive 
http://opencompute.org 9 
 
Table 5: Additional SMART Attributes 
Bytes Attribute Name Attribute Description 
15:0 Medium Units Written Contains the number of 512 byte data 
units the medium has been written; this 
value includes metadata written to the 
non-out-of-band area in the medium. This 
value is reported in thousands (i.e., a 
value of 1 corresponds to 1000 units of 
512 bytes written) and is rounded up. 
When the LBA size is a value other than 
512 bytes, the controller shall convert the 
amount of data written to 512 byte units.   
16 Capacitor Healthˠ An indicator of the health of the 
capacitors (if present).  This shall be 
expressed as a percentage of charge the 
capacitor is able to hold.   
17 Supported Features Bit 0: 1 indicates a super capacitor exists 
Bits 1-7: Reserved 
32:18 Temperature Throttling  Tracks how much performance is 
throttled to prevent overheating.  The 
attribute reports the number of dies 
multiplied by how long the dies are 
turned off (in minutes).  Resets when the 
drive power cycles.  Saturates and does 
not wrap.* 
33 Power Consumption (optional) Current power consumption of NAND, 
Controller and other SSD components in 
Watts.  If the SSD does not have a 
mechanism to measure power, it should 
return 255. 
34 Wear Range Delta Returns the difference between the 
percentage of used endurance of the 
most-worn block and the least worn 
block: 
(% used of most-worn) – (% used of least-
worn) 
35 Unaligned I/O Count of the number of unaligned IOs 
performed by the host.  This counter 
should be resettable and should not wrap. 
33:36 Mapped LBAs Number of LBAs the map is tracking 
511:37 Reserved  
ˠThis requirement is optional if the vendor provides compelling information in the datasheet about the 
high reliability of the capacitors used in the drive 
  



 
10 February 25, 2015 
 
8.1 NVMe 
NVMe drives must support the following attributes and logging 
 Attributes listed in section 5.10.1.2 of the NVMe specification.  
 Vendor-specific log page 0xC0, as defined in Table 5. 
8.2 AHCI 
AHCI drives must support the following Device Statistics log pages (defined in ACS3) through the Get Log 
command 
 General Statistics log page 
 Solid State Device Statistics log page 
 General Error Statistics log page 
 Transport Statistics log page 
 Temperature Statistics log page 
AHCI drives must support the vendor-specific log page 0xa0, as defined in Table 5. 
9 Commands 
The drive must support the commands specified in the NVMe 1.1a and SATA specifications, and must 
also operate with the Microsoft drivers included with Windows since version 8.1 / Windows server 2012 
R2. 
9.1 Firmware Update 
NVMe drives must implement firmware updates according to the process defined in the NVMe 
specification.  The device must support a minimum of 2 slots for firmware update and may support up 
to 7.   
AHCI drives must use the “download microcode” command and its sub-commands (as defined in ACS3): 
3 – Segmented download and 7 – complete download. 
9.2 Disk Reconditioning Tool & Crypto-Erase 
The following commands are necessary to return the OCS SSD as close as possible to Fresh-Out-of-Box 
(FOB) shipping state.  FOB includes resetting all FTL state relating to block-mapping tables and garbage 
collection logic and erase all stale or invalid data from the flash.  



Open Compute Project  Open CloudServer Solid State Drive 
http://opencompute.org 11 
 
The drive must encrypt all data, and the secure erase command must operate quickly by simply erasing 
the key.  NVMe supports secure erase setting of Cryptographic Erase (see section 5.13 Figure 111 for 
more info). 
 NVMe drives must return to FOB state after combination of Format NVM and Crypto-erase 
 AHCI drives must support the Sanitize Device feature set and the CRYPTO SCRAMBLE EXT 
command. 
9.3 Debugging Logs 
The drive must provide access to its debugging logs.  The logs should contain enough information to 
determine root cause.  Their format will be vendor specific with the vendor providing a tool to consume 
the logs.   
 AHCI drives must support the General Purpose Logging (GPL) feature set.  The log is retrieved 
through the Current Device Internal Status Data log page (0x24) 
 NVMe drives will use a Microsoft-specific log to access debugging logs. 
10 Unplanned Power Loss 
This section details requirements for behavior of write cache due to unplanned power loss. 
 High endurance drives must have a non-volatile write cache 
 Low endurance drives may have a volatile write cache 
10.1 Drives with Volatile Write Cache 
A drive with a volatile write cache is one whose data, in DRAM and/or SRAM, is not guaranteed to be 
written to non-volatile media on loss of power.     
10.2 Drives with Non-Volatile Write Cache 
The following types of media are defined as non-volatile caches: 
 volatile media (such as DRAM and SRAM) protected by capacitance 
   non-volatile media 
 drives supporting the PCIe reset Non-Volatile assist signal 
If the drive uses volatile media and capacitor health is compromised, the cache is no longer considered 
nonvolatile, and the drive must disable the volatile write cache and alert the host.   



 
12 February 25, 2015 
 
 NVME drives must alert the host to failed capacitors through the Device Reliability Async event.   
 AHCI drives must use the Device Statistics Notification from the Device Statistics log page.  
10.2.1 System-Assisted NV Write Cache 
In this scenario, drives must flush all data to non-volatile storage within 1s of the PCIe reset (PERST) 
signal.  System voltage will be valid for at least 1s after PERST is asserted.  After receiving the PERST 
signal, the SSD must not drive any pins. 
With this sequence of signals, the drive must not lose or corrupt any user data or metadata, and should 
not require self-contained hold-up capacitance.  Once the whole-system solution is in place, we will 
consider drives supporting this behavior for PCIe reset as having a non-volatile write cache.   
10.2.2 Fast Flushing 
The performance of drives with non-volatile write caches should not be noticeably degraded by flush, 
and the PLP-backed cache(s) should enable fast performance. 
 FUA – forced unit access (for AHCI only) should be fast 
 Flush Cache should not degrade performance 
 SET FEATURE write-cache disable 
The drive should still flush data to flash when the drive has been idle for at least 20ms or power has 
failed.  The host must be able to dynamically disable these performance optimizations. 
11 Data Security 
The drive must implement the subset of TCG protocol methods described in Microsoft’s Encrypted Hard 
Drive Device Guide (called the “eDrive” standard).  Microsoft has published the requirements on MSDN:  
http://msdn.microsoft.com/en-us/library/windows/hardware/br259095.aspx 
Drives must follow the eDrive security standard.   